# T6G (Grand Teton) — schematic netlist excerpt (pin names and nets, part order shuffled) for the footprints in the layout excerpt that follows; sources: Cadence DE-HDL packaged netlist, KiCad conversion of 04192023_DAF0TMB3IC0_F0TG_MB_C_brd_V02_OCP.brd

J54  SCONN20_HSU2101L00007H  SCONN20_HSU2101-L0000-7H IO  pkg HEADER2X10SXK  page 172
  \1\  = PVDD18_S5_P0
  \2\  = HDT_HDR_R_TCK
  \3\  = PRSNT_HDT_R_N
  \4\  = HDT_HDR_R_TMS
  \5\  = GND
  \6\  = HDT_HDR_R_TDI
  \7\  = GND
  \8\  = HDT_HDR_TDO
  \9\  = HDT_HDR_TRST_N_R
  \10\  = HDT_HDR_PWROK
  \11\  = HDT_CPU0_XTRIG_L6
  \12\  = HDT_HDR_RESET_N
  \13\  = HDT_CPU0_XTRIG_L7
  \14\  = NC
  \15\  = HDT_CPU0_XTRIG_L5
  \16\  = HDT_HDR_DBREQ_R_N
  \17\  = GND
  \18\  = HDT_CPU0_HDT_CONN_TESTEN
  \19\  = PVDD18_S5_P0
  \20\  = NC

(kicad_pcb
	(version 20260206)
	(generator "pcbnew")
	(generator_version "10.0")
	(general
		(thickness 1.6)
		(legacy_teardrops no)
	)
	(paper "A4")
	(title_block
		(title "04192023_DAF0TMB3IC0_F0TG_MB_C_brd_V02_OCP.brd")
		(comment 1 "Grand Teton / footprints 3247-3247 of 8354")
	)
	(layers
		(0 "F.Cu" signal "TOP")
		(4 "In1.Cu" signal "GND")
		(6 "In2.Cu" signal "IN1")
		(8 "In3.Cu" signal "GND1")
		(10 "In4.Cu" signal "IN2")
		(12 "In5.Cu" signal "GND2")
		(14 "In6.Cu" signal "IN3")
		(16 "In7.Cu" signal "GND3")
		(18 "In8.Cu" signal "VCC")
		(20 "In9.Cu" signal "VCC1")
		(22 "In10.Cu" signal "GND4")
		(24 "In11.Cu" signal "IN4")
		(26 "In12.Cu" signal "GND5")
		(28 "In13.Cu" signal "IN5")
		(30 "In14.Cu" signal "GND6")
		(32 "In15.Cu" signal "IN6")
		(34 "In16.Cu" signal "GND7")
		(2 "B.Cu" signal "BOTTOM")
		(9 "F.Adhes" user "F.Adhesive")
		(11 "B.Adhes" user "B.Adhesive")
		(13 "F.Paste" user "Package Geometry/Pastemask Top")
		(15 "B.Paste" user "Package Geometry/Pastemask Bottom")
		(5 "F.SilkS" user "Ref Des/Silkscreen Top")
		(7 "B.SilkS" user "Ref Des/Silkscreen Bottom")
		(1 "F.Mask" user "Board Geometry/Soldermask Top")
		(3 "B.Mask" user "Board Geometry/Soldermask Bottom")
		(17 "Dwgs.User" user "User.Drawings")
		(19 "Cmts.User" user "User.Comments")
		(21 "Eco1.User" user "User.Eco1")
		(23 "Eco2.User" user "User.Eco2")
		(25 "Edge.Cuts" user "Board Geometry/Outline")
		(27 "Margin" user)
		(31 "F.CrtYd" user "Package Geometry/Place Bound Top")
		(29 "B.CrtYd" user "Package Geometry/Place Bound Bottom")
		(35 "F.Fab" user "Ref Des/Assembly Top")
		(33 "B.Fab" user "Ref Des/Assembly Bottom")
	)
	(footprint ""
		(layer "F.Cu")
		(at 394.947394 -58.8645 180)
		(property "Reference" "J54"
			(at -0.614172 -7.543292 0)
			(unlocked yes)
			(layer "F.SilkS")
			(effects
				(font
					(size 0.7874 0.5842)
					(thickness 0.1524)
				)
			)
		)
		(property "Value" ""
			(at 0 0 180)
			(layer "F.Fab")
			(effects
				(font
					(size 1.27 1.27)
				)
			)
		)
		(duplicate_pad_numbers_are_jumpers no)
		(fp_line
			(start 2.249932 6.35)
			(end -2.249932 6.35)
			(stroke
				(width 0.1524)
				(type default)
			)
			(layer "F.SilkS")
		)
		(fp_line
			(start 2.249932 6.2738)
			(end 2.249932 6.35)
			(stroke
				(width 0.1524)
				(type default)
			)
			(layer "F.SilkS")
		)
		(fp_line
			(start 2.249932 5.1562)
			(end 2.249932 5.0038)
			(stroke
				(width 0.1524)
				(type default)
			)
			(layer "F.SilkS")
		)
		(fp_line
			(start 2.249932 3.8862)
			(end 2.249932 3.7338)
			(stroke
				(width 0.1524)
				(type default)
			)
			(layer "F.SilkS")
		)
		(fp_line
			(start 2.249932 2.6162)
			(end 2.249932 2.4638)
			(stroke
				(width 0.1524)
				(type default)
			)
			(layer "F.SilkS")
		)
		(fp_line
			(start 2.249932 1.3462)
			(end 2.249932 1.1938)
			(stroke
				(width 0.1524)
				(type default)
			)
			(layer "F.SilkS")
		)
		(fp_line
			(start 2.249932 0.0762)
			(end 2.249932 -0.0762)
			(stroke
				(width 0.1524)
				(type default)
			)
			(layer "F.SilkS")
		)
		(fp_line
			(start 2.249932 -1.1938)
			(end 2.249932 -1.3462)
			(stroke
				(width 0.1524)
				(type default)
			)
			(layer "F.SilkS")
		)
		(fp_line
			(start 2.249932 -2.4638)
			(end 2.249932 -2.6162)
			(stroke
				(width 0.1524)
				(type default)
			)
			(layer "F.SilkS")
		)
		(fp_line
			(start 2.249932 -3.7338)
			(end 2.249932 -3.8862)
			(stroke
				(width 0.1524)
				(type default)
			)
			(layer "F.SilkS")
		)
		(fp_line
			(start 2.249932 -5.0038)
			(end 2.249932 -5.1562)
			(stroke
				(width 0.1524)
				(type default)
			)
			(layer "F.SilkS")
		)
		(fp_line
			(start 2.249932 -6.35)
			(end 2.249932 -6.2738)
			(stroke
				(width 0.1524)
				(type default)
			)
			(layer "F.SilkS")
		)
		(fp_line
			(start -2.249932 6.35)
			(end -2.249932 6.2738)
			(stroke
				(width 0.1524)
				(type default)
			)
			(layer "F.SilkS")
		)
		(fp_line
			(start -2.249932 5.1562)
			(end -2.249932 5.0038)
			(stroke
				(width 0.1524)
				(type default)
			)
			(layer "F.SilkS")
		)
		(fp_line
			(start -2.249932 3.8862)
			(end -2.249932 3.7338)
			(stroke
				(width 0.1524)
				(type default)
			)
			(layer "F.SilkS")
		)
		(fp_line
			(start -2.249932 2.6162)
			(end -2.249932 2.4638)
			(stroke
				(width 0.1524)
				(type default)
			)
			(layer "F.SilkS")
		)
		(fp_line
			(start -2.249932 1.3462)
			(end -2.249932 1.1938)
			(stroke
				(width 0.1524)
				(type default)
			)
			(layer "F.SilkS")
		)
		(fp_line
			(start -2.249932 0.0762)
			(end -2.249932 -0.0762)
			(stroke
				(width 0.1524)
				(type default)
			)
			(layer "F.SilkS")
		)
		(fp_line
			(start -2.249932 -1.1938)
			(end -2.249932 -1.3462)
			(stroke
				(width 0.1524)
				(type default)
			)
			(layer "F.SilkS")
		)
		(fp_line
			(start -2.249932 -2.4638)
			(end -2.249932 -2.6162)
			(stroke
				(width 0.1524)
				(type default)
			)
			(layer "F.SilkS")
		)
		(fp_line
			(start -2.249932 -3.7338)
			(end -2.249932 -3.8862)
			(stroke
				(width 0.1524)
				(type default)
			)
			(layer "F.SilkS")
		)
		(fp_line
			(start -2.249932 -5.0038)
			(end -2.249932 -5.1562)
			(stroke
				(width 0.1524)
				(type default)
			)
			(layer "F.SilkS")
		)
		(fp_line
			(start -2.249932 -6.2738)
			(end -2.249932 -6.35)
			(stroke
				(width 0.1524)
				(type default)
			)
			(layer "F.SilkS")
		)
		(fp_line
			(start -2.249932 -6.35)
			(end 2.249932 -6.35)
			(stroke
				(width 0.1524)
				(type default)
			)
			(layer "F.SilkS")
		)
		(fp_poly
			(pts
				(xy -3.706114 -5.715) (xy -4.722114 -5.207) (xy -4.722114 -6.223)
			)
			(stroke
				(width 0)
				(type default)
			)
			(fill yes)
			(layer "F.SilkS")
		)
		(fp_line
			(start 2.249932 6.35)
			(end -2.249932 6.35)
			(stroke
				(width 0.1)
				(type default)
			)
			(layer "F.Fab")
		)
		(fp_line
			(start 2.249932 -6.35)
			(end 2.249932 6.35)
			(stroke
				(width 0.1)
				(type default)
			)
			(layer "F.Fab")
		)
		(fp_line
			(start -2.249932 6.35)
			(end -2.249932 -6.35)
			(stroke
				(width 0.1)
				(type default)
			)
			(layer "F.Fab")
		)
		(fp_line
			(start -2.249932 -6.35)
			(end 2.249932 -6.35)
			(stroke
				(width 0.1)
				(type default)
			)
			(layer "F.Fab")
		)
		(fp_poly
			(pts
				(xy -4.722114 -6.223) (xy -4.722114 -5.207) (xy -3.706114 -5.715)
			)
			(stroke
				(width 0)
				(type default)
			)
			(fill yes)
			(layer "F.Fab")
		)
		(pad "1" smd rect
			(at -2.359914 -5.715 90)
			(size 0.8636 2.4384)
			(layers "F.Cu" "F.Mask" "F.Paste")
			(net "PVDD18_S5_P0")
		)
		(pad "2" smd rect
			(at 2.359914 -5.715 90)
			(size 0.8636 2.4384)
			(layers "F.Cu" "F.Mask" "F.Paste")
			(net "HDT_HDR_R_TCK")
		)
		(pad "3" smd rect
			(at -2.359914 -4.445 90)
			(size 0.8636 2.4384)
			(layers "F.Cu" "F.Mask" "F.Paste")
			(net "PRSNT_HDT_R_N")
		)
		(pad "4" smd rect
			(at 2.359914 -4.445 90)
			(size 0.8636 2.4384)
			(layers "F.Cu" "F.Mask" "F.Paste")
			(net "HDT_HDR_R_TMS")
		)
		(pad "5" smd rect
			(at -2.359914 -3.175 90)
			(size 0.8636 2.4384)
			(layers "F.Cu" "F.Mask" "F.Paste")
			(net "GND")
		)
		(pad "6" smd rect
			(at 2.359914 -3.175 90)
			(size 0.8636 2.4384)
			(layers "F.Cu" "F.Mask" "F.Paste")
			(net "HDT_HDR_R_TDI")
		)
		(pad "7" smd rect
			(at -2.359914 -1.905 90)
			(size 0.8636 2.4384)
			(layers "F.Cu" "F.Mask" "F.Paste")
			(net "GND")
		)
		(pad "8" smd rect
			(at 2.359914 -1.905 90)
			(size 0.8636 2.4384)
			(layers "F.Cu" "F.Mask" "F.Paste")
			(net "HDT_HDR_TDO")
		)
		(pad "9" smd rect
			(at -2.359914 -0.635 90)
			(size 0.8636 2.4384)
			(layers "F.Cu" "F.Mask" "F.Paste")
			(net "HDT_HDR_TRST_N_R")
		)
		(pad "10" smd rect
			(at 2.359914 -0.635 90)
			(size 0.8636 2.4384)
			(layers "F.Cu" "F.Mask" "F.Paste")
			(net "HDT_HDR_PWROK")
		)
		(pad "11" smd rect
			(at -2.359914 0.635 90)
			(size 0.8636 2.4384)
			(layers "F.Cu" "F.Mask" "F.Paste")
			(net "HDT_CPU0_XTRIG_L6")
		)
		(pad "12" smd rect
			(at 2.359914 0.635 90)
			(size 0.8636 2.4384)
			(layers "F.Cu" "F.Mask" "F.Paste")
			(net "HDT_HDR_RESET_N")
		)
		(pad "13" smd rect
			(at -2.359914 1.905 90)
			(size 0.8636 2.4384)
			(layers "F.Cu" "F.Mask" "F.Paste")
			(net "HDT_CPU0_XTRIG_L7")
		)
		(pad "14" smd rect
			(at 2.359914 1.905 90)
			(size 0.8636 2.4384)
			(layers "F.Cu" "F.Mask" "F.Paste")
			(net "Net_10739")
		)
		(pad "15" smd rect
			(at -2.359914 3.175 90)
			(size 0.8636 2.4384)
			(layers "F.Cu" "F.Mask" "F.Paste")
			(net "HDT_CPU0_XTRIG_L5")
		)
		(pad "16" smd rect
			(at 2.359914 3.175 90)
			(size 0.8636 2.4384)
			(layers "F.Cu" "F.Mask" "F.Paste")
			(net "HDT_HDR_DBREQ_R_N")
		)
		(pad "17" smd rect
			(at -2.359914 4.445 90)
			(size 0.8636 2.4384)
			(layers "F.Cu" "F.Mask" "F.Paste")
			(net "GND")
		)
		(pad "18" smd rect
			(at 2.359914 4.445 90)
			(size 0.8636 2.4384)
			(layers "F.Cu" "F.Mask" "F.Paste")
			(net "HDT_CPU0_HDT_CONN_TESTEN")
		)
		(pad "19" smd rect
			(at -2.359914 5.715 90)
			(size 0.8636 2.4384)
			(layers "F.Cu" "F.Mask" "F.Paste")
			(net "PVDD18_S5_P0")
		)
		(pad "20" smd rect
			(at 2.359914 5.715 90)
			(size 0.8636 2.4384)
			(layers "F.Cu" "F.Mask" "F.Paste")
			(net "Net_10738")
		)
	)
)
